# SCM (Grand Teton) — schematic netlist excerpt (pin names and nets, part order shuffled) for the footprints in the layout excerpt that follows; sources: Cadence DE-HDL packaged netlist, KiCad conversion of 12092022_DA0F0TMDCD0_F0T_Management_Board_D_brd_V3_OCP.brd

R515  Q_RES  33.2 1% CHIP  pkg 0402LF  page 32 : A = JTAG_SCM_PLD_TMS ; B = JTAG_SCM_CONN_TMS
R561  Q_RES  33.2 1% EMPTY  pkg 0402LF  page 21 : A = RST_SPI_BMC_FLASH_R2_N ; B = RST_SPI_FLASH_BUF_N

(kicad_pcb
	(version 20260206)
	(generator "pcbnew")
	(generator_version "10.0")
	(general
		(thickness 1.6)
		(legacy_teardrops no)
	)
	(paper "A4")
	(title_block
		(title "12092022_DA0F0TMDCD0_F0T_Management_Board_D_brd_V3_OCP.brd")
		(comment 1 "Grand Teton / footprints 29-30 of 1440")
	)
	(layers
		(0 "F.Cu" signal "TOP")
		(4 "In1.Cu" signal "GND")
		(6 "In2.Cu" signal "IN1")
		(8 "In3.Cu" signal "GND1")
		(10 "In4.Cu" signal "IN2")
		(12 "In5.Cu" signal "VCC")
		(14 "In6.Cu" signal "VCC1")
		(16 "In7.Cu" signal "IN3")
		(18 "In8.Cu" signal "GND2")
		(20 "In9.Cu" signal "IN4")
		(22 "In10.Cu" signal "GND3")
		(2 "B.Cu" signal "BOTTOM")
		(9 "F.Adhes" user "F.Adhesive")
		(11 "B.Adhes" user "B.Adhesive")
		(13 "F.Paste" user "Package Geometry/Pastemask Top")
		(15 "B.Paste" user "Package Geometry/Pastemask Bottom")
		(5 "F.SilkS" user "Ref Des/Silkscreen Top")
		(7 "B.SilkS" user "Ref Des/Silkscreen Bottom")
		(1 "F.Mask" user "Board Geometry/Soldermask Top")
		(3 "B.Mask" user "Board Geometry/Soldermask Bottom")
		(17 "Dwgs.User" user "User.Drawings")
		(19 "Cmts.User" user "User.Comments")
		(21 "Eco1.User" user "User.Eco1")
		(23 "Eco2.User" user "User.Eco2")
		(25 "Edge.Cuts" user "Board Geometry/Outline")
		(27 "Margin" user)
		(31 "F.CrtYd" user "Package Geometry/Place Bound Top")
		(29 "B.CrtYd" user "Package Geometry/Place Bound Bottom")
		(35 "F.Fab" user "Ref Des/Assembly Top")
		(33 "B.Fab" user "Ref Des/Assembly Bottom")
	)
	(footprint ""
		(layer "F.Cu")
		(at 10.287 -94.615 90)
		(property "Reference" "R515"
			(at 0 0 90)
			(layer "F.SilkS")
			(hide yes)
			(effects
				(font
					(size 1.27 1.27)
				)
			)
		)
		(property "Value" ""
			(at 0 0 90)
			(layer "F.Fab")
			(effects
				(font
					(size 1.27 1.27)
				)
			)
		)
		(duplicate_pad_numbers_are_jumpers no)
		(fp_line
			(start 0.7874 -0.4064)
			(end 0.7874 0.4064)
			(stroke
				(width 0.1524)
				(type default)
			)
			(layer "F.SilkS")
		)
		(fp_line
			(start -0.7874 -0.4064)
			(end 0.7874 -0.4064)
			(stroke
				(width 0.1524)
				(type default)
			)
			(layer "F.SilkS")
		)
		(fp_line
			(start 0.7874 0.4064)
			(end -0.7874 0.4064)
			(stroke
				(width 0.1524)
				(type default)
			)
			(layer "F.SilkS")
		)
		(fp_line
			(start -0.7874 0.4064)
			(end -0.7874 -0.4064)
			(stroke
				(width 0.1524)
				(type default)
			)
			(layer "F.SilkS")
		)
		(fp_line
			(start -0.12065 -0.305054)
			(end -0.12065 -0.2794)
			(stroke
				(width 0.1)
				(type default)
			)
			(layer "F.Fab")
		)
		(fp_line
			(start -0.67945 -0.305054)
			(end -0.12065 -0.305054)
			(stroke
				(width 0.1)
				(type default)
			)
			(layer "F.Fab")
		)
		(fp_line
			(start 0.67945 -0.3048)
			(end 0.67945 0.3048)
			(stroke
				(width 0.1)
				(type default)
			)
			(layer "F.Fab")
		)
		(fp_line
			(start 0.12065 -0.3048)
			(end 0.67945 -0.3048)
			(stroke
				(width 0.1)
				(type default)
			)
			(layer "F.Fab")
		)
		(fp_line
			(start 0.12065 -0.2794)
			(end 0.12065 -0.3048)
			(stroke
				(width 0.1)
				(type default)
			)
			(layer "F.Fab")
		)
		(fp_line
			(start -0.12065 -0.2794)
			(end 0.12065 -0.2794)
			(stroke
				(width 0.1)
				(type default)
			)
			(layer "F.Fab")
		)
		(fp_line
			(start 0.120396 0.2794)
			(end -0.12065 0.2794)
			(stroke
				(width 0.1)
				(type default)
			)
			(layer "F.Fab")
		)
		(fp_line
			(start -0.12065 0.2794)
			(end -0.12065 0.3048)
			(stroke
				(width 0.1)
				(type default)
			)
			(layer "F.Fab")
		)
		(fp_line
			(start 0.67945 0.3048)
			(end 0.120396 0.3048)
			(stroke
				(width 0.1)
				(type default)
			)
			(layer "F.Fab")
		)
		(fp_line
			(start 0.120396 0.3048)
			(end 0.120396 0.2794)
			(stroke
				(width 0.1)
				(type default)
			)
			(layer "F.Fab")
		)
		(fp_line
			(start -0.12065 0.3048)
			(end -0.67945 0.3048)
			(stroke
				(width 0.1)
				(type default)
			)
			(layer "F.Fab")
		)
		(fp_line
			(start -0.67945 0.3048)
			(end -0.67945 -0.305054)
			(stroke
				(width 0.1)
				(type default)
			)
			(layer "F.Fab")
		)
		(pad "1" smd circle
			(at -0.40005 0 90)
			(size 0 0)
			(layers "F.Cu" "F.Mask" "F.Paste")
			(net "JTAG_SCM_PLD_TMS")
		)
		(pad "2" smd circle
			(at 0.40005 0 90)
			(size 0 0)
			(layers "F.Cu" "F.Mask" "F.Paste")
			(net "JTAG_SCM_CONN_TMS")
		)
	)
	(footprint ""
		(layer "F.Cu")
		(at 21.209 -68.834 -90)
		(property "Reference" "R561"
			(at 0 0 270)
			(layer "F.SilkS")
			(hide yes)
			(effects
				(font
					(size 1.27 1.27)
				)
			)
		)
		(property "Value" ""
			(at 0 0 270)
			(layer "F.Fab")
			(effects
				(font
					(size 1.27 1.27)
				)
			)
		)
		(duplicate_pad_numbers_are_jumpers no)
		(fp_line
			(start -0.7874 0.4064)
			(end -0.7874 -0.4064)
			(stroke
				(width 0.1524)
				(type default)
			)
			(layer "F.SilkS")
		)
		(fp_line
			(start 0.7874 0.4064)
			(end -0.7874 0.4064)
			(stroke
				(width 0.1524)
				(type default)
			)
			(layer "F.SilkS")
		)
		(fp_line
			(start -0.7874 -0.4064)
			(end 0.7874 -0.4064)
			(stroke
				(width 0.1524)
				(type default)
			)
			(layer "F.SilkS")
		)
		(fp_line
			(start 0.7874 -0.4064)
			(end 0.7874 0.4064)
			(stroke
				(width 0.1524)
				(type default)
			)
			(layer "F.SilkS")
		)
		(fp_line
			(start -0.67945 0.3048)
			(end -0.67945 -0.305054)
			(stroke
				(width 0.1)
				(type default)
			)
			(layer "F.Fab")
		)
		(fp_line
			(start -0.12065 0.3048)
			(end -0.67945 0.3048)
			(stroke
				(width 0.1)
				(type default)
			)
			(layer "F.Fab")
		)
		(fp_line
			(start 0.120396 0.3048)
			(end 0.120396 0.2794)
			(stroke
				(width 0.1)
				(type default)
			)
			(layer "F.Fab")
		)
		(fp_line
			(start 0.67945 0.3048)
			(end 0.120396 0.3048)
			(stroke
				(width 0.1)
				(type default)
			)
			(layer "F.Fab")
		)
		(fp_line
			(start -0.12065 0.2794)
			(end -0.12065 0.3048)
			(stroke
				(width 0.1)
				(type default)
			)
			(layer "F.Fab")
		)
		(fp_line
			(start 0.120396 0.2794)
			(end -0.12065 0.2794)
			(stroke
				(width 0.1)
				(type default)
			)
			(layer "F.Fab")
		)
		(fp_line
			(start -0.12065 -0.2794)
			(end 0.12065 -0.2794)
			(stroke
				(width 0.1)
				(type default)
			)
			(layer "F.Fab")
		)
		(fp_line
			(start 0.12065 -0.2794)
			(end 0.12065 -0.3048)
			(stroke
				(width 0.1)
				(type default)
			)
			(layer "F.Fab")
		)
		(fp_line
			(start 0.12065 -0.3048)
			(end 0.67945 -0.3048)
			(stroke
				(width 0.1)
				(type default)
			)
			(layer "F.Fab")
		)
		(fp_line
			(start 0.67945 -0.3048)
			(end 0.67945 0.3048)
			(stroke
				(width 0.1)
				(type default)
			)
			(layer "F.Fab")
		)
		(fp_line
			(start -0.67945 -0.305054)
			(end -0.12065 -0.305054)
			(stroke
				(width 0.1)
				(type default)
			)
			(layer "F.Fab")
		)
		(fp_line
			(start -0.12065 -0.305054)
			(end -0.12065 -0.2794)
			(stroke
				(width 0.1)
				(type default)
			)
			(layer "F.Fab")
		)
		(pad "1" smd circle
			(at -0.40005 0 270)
			(size 0 0)
			(layers "F.Cu" "F.Mask" "F.Paste")
			(net "RST_SPI_BMC_FLASH_R2_N")
		)
		(pad "2" smd circle
			(at 0.40005 0 270)
			(size 0 0)
			(layers "F.Cu" "F.Mask" "F.Paste")
			(net "RST_SPI_FLASH_BUF_N")
		)
	)
)
